(kicad_pcb
	(version 20241229)
	(generator "pcbnew")
	(generator_version "9.0")
	(general
		(thickness 1.711)
		(legacy_teardrops no)
	)
	(paper "A4")
	(title_block
		(title "Antmicro Baseboard for Jetson AGX Thor")
		(date "2026-02-18")
		(rev "1.1.0")
		(company "Antmicro Ltd")
		(comment 1 "www.antmicro.com")
		(comment 9 "footprint 123 of 1170 (U78), pads 1-24 of 24")
	)
	(layers
		(0 "F.Cu" signal)
		(4 "In1.Cu" signal)
		(6 "In2.Cu" signal)
		(8 "In3.Cu" signal)
		(10 "In4.Cu" jumper)
		(12 "In5.Cu" signal)
		(14 "In6.Cu" signal)
		(16 "In7.Cu" signal)
		(18 "In8.Cu" signal)
		(2 "B.Cu" signal)
		(9 "F.Adhes" user "F.Adhesive")
		(11 "B.Adhes" user "B.Adhesive")
		(13 "F.Paste" user)
		(15 "B.Paste" user)
		(5 "F.SilkS" user "F.Silkscreen")
		(7 "B.SilkS" user "B.Silkscreen")
		(1 "F.Mask" user)
		(3 "B.Mask" user)
		(17 "Dwgs.User" user "User.Drawings")
		(19 "Cmts.User" user "User.Comments")
		(21 "Eco1.User" user "User.Eco1")
		(23 "Eco2.User" user "User.Eco2")
		(25 "Edge.Cuts" user)
		(27 "Margin" user)
		(31 "F.CrtYd" user "F.Courtyard")
		(29 "B.CrtYd" user "B.Courtyard")
		(35 "F.Fab" user)
		(33 "B.Fab" user)
	)
	(footprint "antmicro-footprints:UQFN-24_2x4mm_P0.4mm_Texas_RJW0024A"
		(layer "F.Cu")
		(at 152.525 104.41 180)
		(property "Reference" "U78"
			(at 3.625 2 0)
			(unlocked yes)
			(layer "F.SilkS")
			(effects
				(font
					(size 0.7 0.7)
					(thickness 0.15)
				)
				(justify left bottom)
			)
		)
		(property "Value" "SN74AXC8T245_UQFN"
			(at 0 3.4 180)
			(unlocked yes)
			(layer "F.Fab")
			(effects
				(font
					(size 0.7 0.7)
					(thickness 0.15)
				)
				(justify left bottom)
			)
		)
		(property "Datasheet" "https://www.ti.com/lit/ds/symlink/sn74axc8t245.pdf?ts=1702327536011"
			(at 0 0 0)
			(layer "F.Fab")
			(hide yes)
			(effects
				(font
					(size 1.27 1.27)
					(thickness 0.15)
				)
			)
		)
		(property "Description" "8-bit dual-supply bus transceiver"
			(at 0 0 0)
			(layer "F.Fab")
			(hide yes)
			(effects
				(font
					(size 1.27 1.27)
					(thickness 0.15)
				)
			)
		)
		(property "MPN" "SN74AXC8T245RJWR"
			(at 0 0 180)
			(unlocked yes)
			(layer "F.Fab")
			(hide yes)
			(effects
				(font
					(size 1 1)
					(thickness 0.15)
				)
			)
		)
		(property "Manufacturer" "Texas Instruments"
			(at 0 0 180)
			(unlocked yes)
			(layer "F.Fab")
			(hide yes)
			(effects
				(font
					(size 1 1)
					(thickness 0.15)
				)
			)
		)
		(property "Author" "Antmicro"
			(at 0 0 180)
			(unlocked yes)
			(layer "F.Fab")
			(hide yes)
			(effects
				(font
					(size 1 1)
					(thickness 0.15)
				)
			)
		)
		(property "License" "Apache-2.0"
			(at 0 0 180)
			(unlocked yes)
			(layer "F.Fab")
			(hide yes)
			(effects
				(font
					(size 1 1)
					(thickness 0.15)
				)
			)
		)
		(sheetname "/SoM_IO/")
		(sheetfile "som_io.kicad_sch")
		(attr smd)
		(pad "1" smd rect
			(at -0.85 -1.8 180)
			(size 0.700001 0.2)
			(layers "F.Cu" "F.Mask")
			(net 11 "+1V8")
			(pinfunction "DIR1")
			(pintype "input")
		)
		(pad "2" smd rect
			(at -0.85 -1.4 180)
			(size 0.700001 0.2)
			(layers "F.Cu" "F.Mask")
			(net 625 "/SoM_IO/SFP_LEDY_1V8")
			(pinfunction "A1")
			(pintype "bidirectional")
		)
		(pad "3" smd rect
			(at -0.7 -1 180)
			(size 1 0.2)
			(layers "F.Cu" "F.Mask")
			(net 643 "/SoM_IO/SFP_LEDG_1V8")
			(pinfunction "A2")
			(pintype "bidirectional")
		)
		(pad "4" smd rect
			(at -0.7 -0.6 180)
			(size 1 0.2)
			(layers "F.Cu" "F.Mask")
			(net 1 "GND")
			(pinfunction "A3")
			(pintype "bidirectional")
		)
		(pad "5" smd rect
			(at -0.7 -0.2 180)
			(size 1 0.2)
			(layers "F.Cu" "F.Mask")
			(net 689 "/SoM_IO/USBC2_PEN_1V8")
			(pinfunction "A4")
			(pintype "bidirectional")
		)
		(pad "6" smd rect
			(at -0.7 0.2 180)
			(size 1 0.2)
			(layers "F.Cu" "F.Mask")
			(net 1242 "/SoM_IO/USBC2_ID_1V8")
			(pinfunction "A5")
			(pintype "bidirectional")
		)
		(pad "7" smd rect
			(at -0.7 0.6 180)
			(size 1 0.2)
			(layers "F.Cu" "F.Mask")
			(net 692 "/SoM_IO/~{USBC2_INT}_1V8")
			(pinfunction "A6")
			(pintype "bidirectional")
		)
		(pad "8" smd rect
			(at -0.7 1 180)
			(size 1 0.2)
			(layers "F.Cu" "F.Mask")
			(net 1244 "/SoM_IO/USBC2_VBUS_DET_1V8")
			(pinfunction "A7")
			(pintype "bidirectional")
		)
		(pad "9" smd rect
			(at -0.85 1.4 180)
			(size 0.700001 0.2)
			(layers "F.Cu" "F.Mask")
			(net 780 "/SoM_IO/~{PDC_I2C1_IRQ}_1V8")
			(pinfunction "A8")
			(pintype "bidirectional")
		)
		(pad "10" smd rect
			(at -0.85 1.8 180)
			(size 0.700001 0.2)
			(layers "F.Cu" "F.Mask")
			(net 11 "+1V8")
			(pinfunction "DIR2")
			(pintype "input")
		)
		(pad "11" smd rect
			(at -0.199999 1.825 270)
			(size 0.750001 0.2)
			(layers "F.Cu" "F.Mask")
			(net 1 "GND")
			(pinfunction "GND")
			(pintype "power_in")
		)
		(pad "12" smd rect
			(at 0.199999 1.825 270)
			(size 0.750001 0.2)
			(layers "F.Cu" "F.Mask")
			(net 1 "GND")
			(pinfunction "GND")
			(pintype "passive")
		)
		(pad "13" smd rect
			(at 0.85 1.8 180)
			(size 0.700001 0.2)
			(layers "F.Cu" "F.Mask")
			(net 954 "/SoM_IO/~{PDC_I2C1_IRQ}")
			(pinfunction "B8")
			(pintype "bidirectional")
		)
		(pad "14" smd rect
			(at 0.85 1.4 180)
			(size 0.700001 0.2)
			(layers "F.Cu" "F.Mask")
			(net 1018 "/Recovery USB/USBC2_VBUS_DET")
			(pinfunction "B7")
			(pintype "bidirectional")
		)
		(pad "15" smd rect
			(at 0.7 1 180)
			(size 1 0.2)
			(layers "F.Cu" "F.Mask")
			(net 1026 "/Recovery USB/~{USBC2_INT}")
			(pinfunction "B6")
			(pintype "bidirectional")
		)
		(pad "16" smd rect
			(at 0.7 0.6 180)
			(size 1 0.2)
			(layers "F.Cu" "F.Mask")
			(net 889 "/Recovery USB/USBC2_ID")
			(pinfunction "B5")
			(pintype "bidirectional")
		)
		(pad "17" smd rect
			(at 0.7 0.2 180)
			(size 1 0.2)
			(layers "F.Cu" "F.Mask")
			(net 1017 "/Recovery USB/USBC2_PEN")
			(pinfunction "B4")
			(pintype "bidirectional")
		)
		(pad "18" smd rect
			(at 0.7 -0.2 180)
			(size 1 0.2)
			(layers "F.Cu" "F.Mask")
			(net 1340 "unconnected-(U78-B3-Pad18)")
			(pinfunction "B3")
			(pintype "bidirectional+no_connect")
		)
		(pad "19" smd rect
			(at 0.7 -0.6 180)
			(size 1 0.2)
			(layers "F.Cu" "F.Mask")
			(net 1004 "/SFP/SFP_LEDG")
			(pinfunction "B2")
			(pintype "bidirectional")
		)
		(pad "20" smd rect
			(at 0.7 -1 180)
			(size 1 0.2)
			(layers "F.Cu" "F.Mask")
			(net 1003 "/SFP/SFP_LEDY")
			(pinfunction "B1")
			(pintype "bidirectional")
		)
		(pad "21" smd rect
			(at 0.85 -1.4 180)
			(size 0.700001 0.2)
			(layers "F.Cu" "F.Mask")
			(net 1 "GND")
			(pinfunction "OE_N")
			(pintype "input")
		)
		(pad "22" smd rect
			(at 0.85 -1.8 180)
			(size 0.700001 0.2)
			(layers "F.Cu" "F.Mask")
			(net 2 "+3V3")
			(pinfunction "VCCB")
			(pintype "power_in")
		)
		(pad "23" smd rect
			(at 0.199999 -1.825 270)
			(size 0.750001 0.2)
			(layers "F.Cu" "F.Mask")
			(net 2 "+3V3")
			(pinfunction "VCCB")
			(pintype "passive")
		)
		(pad "24" smd rect
			(at -0.199999 -1.825 270)
			(size 0.750001 0.2)
			(layers "F.Cu" "F.Mask")
			(net 11 "+1V8")
			(pinfunction "VCCA")
			(pintype "power_in")
		)
	)
)
